FILE_TYPE = CONNECTIVITY;
{Allegro Design Entry HDL 17.2-2016 S081 (4005846) 1/11/2022}
"PAGE_NUMBER" = 113;
0"NC";
1"P12V_S3_AUX_CPU1_NVDIMM\g";
2"P12V_S3_AUX_CPU1_NVDIMM\g";
3"P3V3_AUX\g";
4"P3V3_AUX\g";
5"GND\g";
6"GND\g";
7"GND\g";
8"GND\g";
9"GND\g";
10"M_H_CPU1_SA_DQ<31:0>";
11"M_H_CPU1_SA_CB<7:0>";
12"M_H_CPU1_SB_CB<7:0>";
13"M_H_CPU1_SA_CA<6:0>";
14"M_H_CPU1_SB_CA<6:0>";
15"M_H_CPU1_SB_DQ<31:0>";
16"M_H_CPU1_SB_DQS_DP<9:0>";
17"M_H_CPU1_SA_DQS_DP<9:0>";
18"M_H_CPU1_SB_DQS_DN<9:0>";
19"M_H_CPU1_SA_DQS_DN<9:0>";
20"I3C_SPD_DDREFGH_CPU1_LVC1_SDA";
21"I3C_SPD_DDREFGH_CPU1_LVC1_SCL_R8";
22"RST_M_GH_CPU1_FPGA_N";
23"M_H_CPU1_ALERT_N";
24"I3C_SPD_DDREFGH_CPU1_LVC1_SCL";
25"TP_CHH_CPU1_DIMM2_FRU_4";
26"TP_CHH_CPU1_DIMM2_FRU_3";
27"TP_CHH_CPU1_DIMM2_FRU_5";
28"TP_CHH_CPU1_DIMM2_FRU_6";
29"PWRGD_CHH_CPU1_DIMM2";
30"PD_CHH_CPU1_DIMM2_SAA";
31"M_H_CPU1_SB_DQ<28>";
32"M_H_CPU1_SA_DQ<1>";
33"M_H_CPU1_SA_CB<5>";
34"TP_CHH_CPU1_DIMM2_FRU_2";
35"M_H_CPU1_SB_CB<6>";
36"M_H_CPU1_SA_CB<0>";
37"M_H_CPU1_SB_DQS_DN<5>";
38"M_H_CPU1_SA_DQS_DN<9>";
39"M_H_CPU1_SA_DQS_DN<8>";
40"M_H_CPU1_SA_DQS_DN<6>";
41"M_H_CPU1_SA_DQS_DN<7>";
42"M_H_CPU1_SA_DQS_DN<5>";
43"M_H_CPU1_SA_DQS_DN<4>";
44"M_H_CPU1_SA_DQS_DN<3>";
45"M_H_CPU1_SA_DQS_DN<1>";
46"M_H_CPU1_SA_DQS_DN<2>";
47"M_H_CPU1_SA_DQS_DN<0>";
48"M_H_CPU1_SB_DQS_DN<9>";
49"M_H_CPU1_SB_DQS_DN<8>";
50"M_H_CPU1_SB_DQS_DN<7>";
51"M_H_CPU1_SB_DQS_DN<6>";
52"M_H_CPU1_SB_DQS_DN<4>";
53"M_H_CPU1_SB_DQS_DN<3>";
54"M_H_CPU1_SB_DQS_DN<2>";
55"M_H_CPU1_SB_DQS_DN<0>";
56"M_H_CPU1_SB_DQS_DN<1>";
57"M_H_CPU1_SA_DQS_DP<9>";
58"M_H_CPU1_SA_DQS_DP<8>";
59"M_H_CPU1_SA_DQS_DP<7>";
60"M_H_CPU1_SA_DQS_DP<6>";
61"M_H_CPU1_SA_DQS_DP<5>";
62"M_H_CPU1_SA_DQS_DP<4>";
63"M_H_CPU1_SA_DQS_DP<3>";
64"M_H_CPU1_SA_DQS_DP<2>";
65"M_H_CPU1_SA_DQS_DP<1>";
66"M_H_CPU1_SA_DQS_DP<0>";
67"M_H_CPU1_SB_DQS_DP<9>";
68"M_H_CPU1_SB_DQS_DP<8>";
69"M_H_CPU1_SB_DQS_DP<7>";
70"M_H_CPU1_SB_DQS_DP<6>";
71"M_H_CPU1_SB_DQS_DP<5>";
72"M_H_CPU1_SB_DQS_DP<4>";
73"M_H_CPU1_SB_DQS_DP<3>";
74"M_H_CPU1_SB_DQS_DP<2>";
75"M_H_CPU1_SB_DQS_DP<1>";
76"M_H_CPU1_SB_DQS_DP<0>";
77"M_H_CPU1_SB_CB<3>";
78"M_H_CPU1_SB_CB<4>";
79"M_H_CPU1_SB_CB<0>";
80"M_H_CPU1_SA_CB<7>";
81"M_H_CPU1_SA_DQ<10>";
82"M_H_CPU1_SA_DQ<9>";
83"M_H_CPU1_SA_DQ<8>";
84"M_H_CPU1_SA_DQ<7>";
85"PD_CHH_CPU1_DIMM2_SAA";
86"M_H_CPU1_SB_RSP<1>";
87"M_H_CPU1_SA_RSP<1>";
88"TP_CHH_CPU1_DIMM2_FRU_0";
89"TP_CHH_CPU1_DIMM2_FRU_1";
90"M_H_CPU1_SA_CA<4>";
91"M_H_CPU1_CLK_DN<1>";
92"M_H_CPU1_CLK_DP<1>";
93"M_H_CPU1_SA_DQ<16>";
94"M_H_CPU1_SA_DQ<17>";
95"M_H_CPU1_SB_CB<5>";
96"M_H_CPU1_SB_DQ<11>";
97"M_H_CPU1_SA_DQ<28>";
98"M_H_CPU1_SB_CS_N<3>";
99"M_H_CPU1_SB_DQ<26>";
100"M_H_CPU1_SB_DQ<27>";
101"M_H_CPU1_SB_PAR";
102"M_H_CPU1_SA_PAR";
103"M_H_CPU1_SB_DQ<0>";
104"M_H_CPU1_SB_DQ<1>";
105"M_H_CPU1_SB_DQ<2>";
106"M_H_CPU1_SB_DQ<3>";
107"M_H_CPU1_SB_DQ<4>";
108"M_H_CPU1_SB_DQ<5>";
109"M_H_CPU1_SB_DQ<6>";
110"M_H_CPU1_SB_DQ<7>";
111"M_H_CPU1_SB_DQ<8>";
112"M_H_CPU1_SB_DQ<9>";
113"M_H_CPU1_SB_DQ<10>";
114"M_H_CPU1_SB_DQ<12>";
115"M_H_CPU1_SB_DQ<13>";
116"M_H_CPU1_SB_DQ<14>";
117"M_H_CPU1_SB_DQ<15>";
118"M_H_CPU1_SB_DQ<16>";
119"M_H_CPU1_SB_DQ<17>";
120"M_H_CPU1_SB_DQ<18>";
121"M_H_CPU1_SB_DQ<19>";
122"M_H_CPU1_SB_DQ<20>";
123"M_H_CPU1_SB_DQ<21>";
124"M_H_CPU1_SB_DQ<22>";
125"M_H_CPU1_SB_DQ<23>";
126"M_H_CPU1_SB_DQ<24>";
127"M_H_CPU1_SB_DQ<25>";
128"M_H_CPU1_SB_DQ<29>";
129"M_H_CPU1_SB_DQ<30>";
130"M_H_CPU1_SB_DQ<31>";
131"M_H_CPU1_SA_DQ<0>";
132"M_H_CPU1_SA_DQ<2>";
133"M_H_CPU1_SA_DQ<3>";
134"M_H_CPU1_SA_DQ<4>";
135"M_H_CPU1_SA_DQ<5>";
136"M_H_CPU1_SA_DQ<6>";
137"M_H_CPU1_SA_DQ<11>";
138"M_H_CPU1_SA_DQ<12>";
139"M_H_CPU1_SA_DQ<13>";
140"M_H_CPU1_SA_DQ<14>";
141"M_H_CPU1_SA_DQ<15>";
142"M_H_CPU1_SA_DQ<18>";
143"M_H_CPU1_SA_DQ<19>";
144"M_H_CPU1_SA_DQ<20>";
145"M_H_CPU1_SA_DQ<21>";
146"M_H_CPU1_SA_DQ<22>";
147"M_H_CPU1_SA_DQ<23>";
148"M_H_CPU1_SA_DQ<24>";
149"M_H_CPU1_SA_DQ<25>";
150"M_H_CPU1_SA_DQ<26>";
151"M_H_CPU1_SA_DQ<27>";
152"M_H_CPU1_SA_DQ<29>";
153"M_H_CPU1_SA_DQ<30>";
154"M_H_CPU1_SA_CS_N<3>";
155"M_H_CPU1_SB_CS_N<2>";
156"M_H_CPU1_SA_CS_N<2>";
157"M_H_CPU1_SB_CB<1>";
158"M_H_CPU1_SB_CB<2>";
159"M_H_CPU1_SA_CB<2>";
160"M_H_CPU1_SA_CB<3>";
161"M_H_CPU1_SA_CB<6>";
162"M_H_CPU1_SB_CA<6>";
163"M_H_CPU1_SA_CA<6>";
164"M_H_CPU1_SB_CA<5>";
165"M_H_CPU1_SA_CA<5>";
166"M_H_CPU1_SB_CA<4>";
167"M_H_CPU1_SB_CA<3>";
168"M_H_CPU1_SA_CA<3>";
169"M_H_CPU1_SB_CA<2>";
170"M_H_CPU1_SA_CA<2>";
171"M_H_CPU1_SB_CA<1>";
172"M_H_CPU1_SA_CA<1>";
173"M_H_CPU1_SB_CA<0>";
174"M_H_CPU1_SA_CA<0>";
175"M_H_CPU1_SB_CB<7>";
176"M_H_CPU1_SA_CB<1>";
177"M_H_CPU1_SA_CB<4>";
178"M_H_CPU1_SA_DQ<31>";
%"UNIVERSAL_GND"
"1","(-3675,75)","0","logical_power","I1";
;
HDL_POWER"GND"
CDS_LIB"logical_power";
"A"9;
%"TAP"
"1","(-2250,4050)","0","standard","I100";
;
CDS_LIB"standard"
BODY_TYPE"PLUMBING"
HDL_TAP"TRUE";
"B \NAC \NWC"10;
"S \NAC"
BN"23"147;
%"TAP"
"1","(-2250,4100)","0","standard","I101";
;
CDS_LIB"standard"
BODY_TYPE"PLUMBING"
HDL_TAP"TRUE";
"B \NAC \NWC"10;
"S \NAC"
BN"24"148;
%"TAP"
"1","(-2250,4000)","0","standard","I102";
;
CDS_LIB"standard"
BODY_TYPE"PLUMBING"
HDL_TAP"TRUE";
"B \NAC \NWC"10;
"S \NAC"
BN"22"146;
%"TAP"
"1","(-2250,3900)","0","standard","I103";
;
CDS_LIB"standard"
BODY_TYPE"PLUMBING"
HDL_TAP"TRUE";
"B \NAC \NWC"10;
"S \NAC"
BN"20"144;
%"TAP"
"1","(-2250,4300)","0","standard","I104";
;
CDS_LIB"standard"
BODY_TYPE"PLUMBING"
HDL_TAP"TRUE";
"B \NAC \NWC"10;
"S \NAC"
BN"28"97;
%"TAP"
"1","(-2250,4250)","0","standard","I105";
;
CDS_LIB"standard"
BODY_TYPE"PLUMBING"
HDL_TAP"TRUE";
"B \NAC \NWC"10;
"S \NAC"
BN"27"151;
%"TAP"
"1","(-2250,4350)","0","standard","I106";
;
CDS_LIB"standard"
BODY_TYPE"PLUMBING"
HDL_TAP"TRUE";
"B \NAC \NWC"10;
"S \NAC"
BN"29"152;
%"TAP"
"1","(-2250,4200)","0","standard","I107";
;
CDS_LIB"standard"
BODY_TYPE"PLUMBING"
HDL_TAP"TRUE";
"B \NAC \NWC"10;
"S \NAC"
BN"26"150;
%"TAP"
"1","(-2250,4150)","0","standard","I108";
;
CDS_LIB"standard"
BODY_TYPE"PLUMBING"
HDL_TAP"TRUE";
"B \NAC \NWC"10;
"S \NAC"
BN"25"149;
%"TAP"
"1","(-3900,4450)","2","standard","I110";
;
CDS_LIB"standard"
BODY_TYPE"PLUMBING"
HDL_TAP"TRUE";
"B \NAC \NWC"13;
"S \NAC"
BN"6"163;
%"TAP"
"1","(-3900,4400)","2","standard","I111";
;
CDS_LIB"standard"
BODY_TYPE"PLUMBING"
HDL_TAP"TRUE";
"B \NAC \NWC"13;
"S \NAC"
BN"5"165;
%"TAP"
"1","(-2250,4400)","0","standard","I112";
;
CDS_LIB"standard"
BODY_TYPE"PLUMBING"
HDL_TAP"TRUE";
"B \NAC \NWC"10;
"S \NAC"
BN"30"153;
%"TAP"
"1","(-2250,4450)","0","standard","I113";
;
CDS_LIB"standard"
BODY_TYPE"PLUMBING"
HDL_TAP"TRUE";
"B \NAC \NWC"10;
"S \NAC"
BN"31"178;
%"UNIVERSAL_GND"
"1","(-525,200)","0","logical_power","I114";
;
HDL_POWER"GND"
CDS_LIB"logical_power";
"A"8;
%"UNIVERSAL_GND"
"1","(1100,200)","0","logical_power","I115";
;
HDL_POWER"GND"
CDS_LIB"logical_power";
"A"7;
%"Q_CAP"
"1","(-525,575)","0","pure_quanta","I116";
;
PART_NUMBER"CH5221MEB00"
VALUE"2.2UF"
PACK_TYPE"C0402"
MATERIAL"X6S"
TOLERANCE"20%"
VOLTAGE"6.3V"
$LOCATION"C72"
CDS_LIB"pure_quanta"
$LOCATION"C72"
CDS_LOCATION"C72"
$SEC"1"
CDS_SEC"1";
"B"
$PN"2"8;
"A"
$PN"1"3;
%"VCC_CORE"
"1","(-525,900)","0","logical_power","I117";
;
HDL_POWER"P3V3_AUX"
CDS_LIB"logical_power";
"A"3;
%"VCC_CORE"
"1","(-4725,2325)","0","logical_power","I12";
;
HDL_POWER"P3V3_AUX"
CDS_LIB"logical_power";
"A"4;
%"Q_CAP"
"1","(475,575)","0","pure_quanta","I120";
;
PART_NUMBER"CH6103KEA00"
TOLERANCE"10%"
VOLTAGE"16V"
VALUE"10UF"
MATERIAL"X6S"
PACK_TYPE"C0805"
$LOCATION"C73"
CDS_LIB"pure_quanta"
$LOCATION"C73"
CDS_LOCATION"C73"
$SEC"1"
CDS_SEC"1";
"B"
$PN"2"7;
"A"
$PN"1"2;
%"VCC_CORE"
"1","(475,900)","0","logical_power","I121";
;
HDL_POWER"P12V_S3_AUX_CPU1_NVDIMM"
CDS_LIB"logical_power";
"A"2;
%"Q_CAP"
"1","(1100,575)","0","pure_quanta","I122";
;
PART_NUMBER"CH6103KEA00"
MATERIAL"X6S"
PACK_TYPE"C0805"
VALUE"10UF"
VOLTAGE"16V"
TOLERANCE"10%"
$LOCATION"C74"
CDS_LIB"pure_quanta"
$LOCATION"C74"
CDS_LOCATION"C74"
$SEC"1"
CDS_SEC"1";
"B"
$PN"2"7;
"A"
$PN"1"2;
%"UNIVERSAL_GND"
"1","(2175,750)","0","logical_power","I123";
;
HDL_POWER"GND"
CDS_LIB"logical_power";
"A"6;
%"TAP"
"1","(500,2500)","0","standard","I124";
;
CDS_LIB"standard"
BODY_TYPE"PLUMBING"
HDL_TAP"TRUE";
"B \NAC \NWC"16;
"S \NAC"
BN"0"76;
%"TAP"
"1","(500,2800)","0","standard","I125";
;
CDS_LIB"standard"
BODY_TYPE"PLUMBING"
HDL_TAP"TRUE";
"B \NAC \NWC"16;
"S \NAC"
BN"3"73;
%"TAP"
"1","(500,2700)","0","standard","I126";
;
CDS_LIB"standard"
BODY_TYPE"PLUMBING"
HDL_TAP"TRUE";
"B \NAC \NWC"16;
"S \NAC"
BN"2"74;
%"TAP"
"1","(500,2600)","0","standard","I127";
;
CDS_LIB"standard"
BODY_TYPE"PLUMBING"
HDL_TAP"TRUE";
"B \NAC \NWC"16;
"S \NAC"
BN"1"75;
%"TAP"
"1","(675,2550)","0","standard","I128";
;
CDS_LIB"standard"
BODY_TYPE"PLUMBING"
HDL_TAP"TRUE";
"B \NAC \NWC"18;
"S \NAC"
BN"1"56;
%"TAP"
"1","(675,2450)","0","standard","I129";
;
CDS_LIB"standard"
BODY_TYPE"PLUMBING"
HDL_TAP"TRUE";
"B \NAC \NWC"18;
"S \NAC"
BN"0"55;
%"TAP"
"1","(-3900,2250)","2","standard","I13";
;
CDS_LIB"standard"
BODY_TYPE"PLUMBING"
HDL_TAP"TRUE";
"B \NAC \NWC"12;
"S \NAC"
BN"0"79;
%"TAP"
"1","(675,2650)","0","standard","I130";
;
CDS_LIB"standard"
BODY_TYPE"PLUMBING"
HDL_TAP"TRUE";
"B \NAC \NWC"18;
"S \NAC"
BN"2"54;
%"TAP"
"1","(675,2750)","0","standard","I131";
;
CDS_LIB"standard"
BODY_TYPE"PLUMBING"
HDL_TAP"TRUE";
"B \NAC \NWC"18;
"S \NAC"
BN"3"53;
%"TAP"
"1","(500,3000)","0","standard","I132";
;
CDS_LIB"standard"
BODY_TYPE"PLUMBING"
HDL_TAP"TRUE";
"B \NAC \NWC"16;
"S \NAC"
BN"5"71;
%"TAP"
"1","(500,2900)","0","standard","I133";
;
CDS_LIB"standard"
BODY_TYPE"PLUMBING"
HDL_TAP"TRUE";
"B \NAC \NWC"16;
"S \NAC"
BN"4"72;
%"TAP"
"1","(500,3300)","0","standard","I134";
;
CDS_LIB"standard"
BODY_TYPE"PLUMBING"
HDL_TAP"TRUE";
"B \NAC \NWC"16;
"S \NAC"
BN"8"68;
%"TAP"
"1","(500,3200)","0","standard","I135";
;
CDS_LIB"standard"
BODY_TYPE"PLUMBING"
HDL_TAP"TRUE";
"B \NAC \NWC"16;
"S \NAC"
BN"7"69;
%"TAP"
"1","(500,3100)","0","standard","I136";
;
CDS_LIB"standard"
BODY_TYPE"PLUMBING"
HDL_TAP"TRUE";
"B \NAC \NWC"16;
"S \NAC"
BN"6"70;
%"TAP"
"1","(675,2950)","0","standard","I137";
;
CDS_LIB"standard"
BODY_TYPE"PLUMBING"
HDL_TAP"TRUE";
"B \NAC \NWC"18;
"S \NAC"
BN"5"37;
%"TAP"
"1","(675,2850)","0","standard","I138";
;
CDS_LIB"standard"
BODY_TYPE"PLUMBING"
HDL_TAP"TRUE";
"B \NAC \NWC"18;
"S \NAC"
BN"4"52;
%"TAP"
"1","(675,3050)","0","standard","I139";
;
CDS_LIB"standard"
BODY_TYPE"PLUMBING"
HDL_TAP"TRUE";
"B \NAC \NWC"18;
"S \NAC"
BN"6"51;
%"TAP"
"1","(675,3150)","0","standard","I140";
;
CDS_LIB"standard"
BODY_TYPE"PLUMBING"
HDL_TAP"TRUE";
"B \NAC \NWC"18;
"S \NAC"
BN"7"50;
%"TAP"
"1","(675,3250)","0","standard","I141";
;
CDS_LIB"standard"
BODY_TYPE"PLUMBING"
HDL_TAP"TRUE";
"B \NAC \NWC"18;
"S \NAC"
BN"8"49;
%"TAP"
"1","(500,3550)","0","standard","I142";
;
CDS_LIB"standard"
BODY_TYPE"PLUMBING"
HDL_TAP"TRUE";
"B \NAC \NWC"17;
"S \NAC"
BN"0"66;
%"TAP"
"1","(500,3400)","0","standard","I143";
;
CDS_LIB"standard"
BODY_TYPE"PLUMBING"
HDL_TAP"TRUE";
"B \NAC \NWC"16;
"S \NAC"
BN"9"67;
%"TAP"
"1","(500,3850)","0","standard","I144";
;
CDS_LIB"standard"
BODY_TYPE"PLUMBING"
HDL_TAP"TRUE";
"B \NAC \NWC"17;
"S \NAC"
BN"3"63;
%"TAP"
"1","(500,3750)","0","standard","I145";
;
CDS_LIB"standard"
BODY_TYPE"PLUMBING"
HDL_TAP"TRUE";
"B \NAC \NWC"17;
"S \NAC"
BN"2"64;
%"TAP"
"1","(500,3650)","0","standard","I146";
;
CDS_LIB"standard"
BODY_TYPE"PLUMBING"
HDL_TAP"TRUE";
"B \NAC \NWC"17;
"S \NAC"
BN"1"65;
%"TAP"
"1","(675,3350)","0","standard","I147";
;
CDS_LIB"standard"
BODY_TYPE"PLUMBING"
HDL_TAP"TRUE";
"B \NAC \NWC"18;
"S \NAC"
BN"9"48;
%"TAP"
"1","(675,3600)","0","standard","I148";
;
CDS_LIB"standard"
BODY_TYPE"PLUMBING"
HDL_TAP"TRUE";
"B \NAC \NWC"19;
"S \NAC"
BN"1"45;
%"TAP"
"1","(675,3500)","0","standard","I149";
;
CDS_LIB"standard"
BODY_TYPE"PLUMBING"
HDL_TAP"TRUE";
"B \NAC \NWC"19;
"S \NAC"
BN"0"47;
%"TAP"
"1","(675,3700)","0","standard","I150";
;
CDS_LIB"standard"
BODY_TYPE"PLUMBING"
HDL_TAP"TRUE";
"B \NAC \NWC"19;
"S \NAC"
BN"2"46;
%"TAP"
"1","(675,3800)","0","standard","I151";
;
CDS_LIB"standard"
BODY_TYPE"PLUMBING"
HDL_TAP"TRUE";
"B \NAC \NWC"19;
"S \NAC"
BN"3"44;
%"TAP"
"1","(500,3950)","0","standard","I152";
;
CDS_LIB"standard"
BODY_TYPE"PLUMBING"
HDL_TAP"TRUE";
"B \NAC \NWC"17;
"S \NAC"
BN"4"62;
%"TAP"
"1","(500,4050)","0","standard","I153";
;
CDS_LIB"standard"
BODY_TYPE"PLUMBING"
HDL_TAP"TRUE";
"B \NAC \NWC"17;
"S \NAC"
BN"5"61;
%"TAP"
"1","(500,4350)","0","standard","I154";
;
CDS_LIB"standard"
BODY_TYPE"PLUMBING"
HDL_TAP"TRUE";
"B \NAC \NWC"17;
"S \NAC"
BN"8"58;
%"TAP"
"1","(500,4250)","0","standard","I155";
;
CDS_LIB"standard"
BODY_TYPE"PLUMBING"
HDL_TAP"TRUE";
"B \NAC \NWC"17;
"S \NAC"
BN"7"59;
%"TAP"
"1","(500,4150)","0","standard","I156";
;
CDS_LIB"standard"
BODY_TYPE"PLUMBING"
HDL_TAP"TRUE";
"B \NAC \NWC"17;
"S \NAC"
BN"6"60;
%"TAP"
"1","(675,3900)","0","standard","I157";
;
CDS_LIB"standard"
BODY_TYPE"PLUMBING"
HDL_TAP"TRUE";
"B \NAC \NWC"19;
"S \NAC"
BN"4"43;
%"TAP"
"1","(675,4100)","0","standard","I158";
;
CDS_LIB"standard"
BODY_TYPE"PLUMBING"
HDL_TAP"TRUE";
"B \NAC \NWC"19;
"S \NAC"
BN"6"40;
%"TAP"
"1","(675,4000)","0","standard","I159";
;
CDS_LIB"standard"
BODY_TYPE"PLUMBING"
HDL_TAP"TRUE";
"B \NAC \NWC"19;
"S \NAC"
BN"5"42;
%"TAP"
"1","(675,4200)","0","standard","I160";
;
CDS_LIB"standard"
BODY_TYPE"PLUMBING"
HDL_TAP"TRUE";
"B \NAC \NWC"19;
"S \NAC"
BN"7"41;
%"TAP"
"1","(675,4300)","0","standard","I161";
;
CDS_LIB"standard"
BODY_TYPE"PLUMBING"
HDL_TAP"TRUE";
"B \NAC \NWC"19;
"S \NAC"
BN"8"39;
%"TAP"
"1","(500,4450)","0","standard","I165";
;
CDS_LIB"standard"
BODY_TYPE"PLUMBING"
HDL_TAP"TRUE";
"B \NAC \NWC"17;
"S \NAC"
BN"9"57;
%"TAP"
"1","(675,4400)","0","standard","I166";
;
CDS_LIB"standard"
BODY_TYPE"PLUMBING"
HDL_TAP"TRUE";
"B \NAC \NWC"19;
"S \NAC"
BN"9"38;
%"VCC_CORE"
"1","(2175,5000)","0","logical_power","I169";
;
HDL_POWER"P12V_S3_AUX_CPU1_NVDIMM"
CDS_LIB"logical_power";
"A"1;
%"UNIVERSAL_GND"
"1","(3875,750)","0","logical_power","I171";
;
HDL_POWER"GND"
CDS_LIB"logical_power";
"A"5;
%"TAP"
"1","(-3900,2500)","2","standard","I175";
;
CDS_LIB"standard"
BODY_TYPE"PLUMBING"
HDL_TAP"TRUE";
"B \NAC \NWC"12;
"S \NAC"
BN"5"95;
%"TAP"
"1","(-3900,2450)","2","standard","I176";
;
CDS_LIB"standard"
BODY_TYPE"PLUMBING"
HDL_TAP"TRUE";
"B \NAC \NWC"12;
"S \NAC"
BN"4"78;
%"SCONN288_ADR50017P087CC"
"3","(3025,2825)","0","pure_quanta","I177";
;
PART_NUMBER"DFHST8FS460"
MATERIAL"IO"
PART_TYPE"SMLF"
VALUE"SCONN288_ADR50017-P087CC"
$LOCATION"J32"
CDS_LIB"pure_quanta"
CDS_LMAN_SYM_OUTLINE"-450,1775,450,-1775"
NEEDS_NO_SIZE"TRUE"
CDS_LOCATION"J32"
$SEC"3"
CDS_SEC"3";
"G3"
$PN"G3"5;
"G2"
$PN"G2"5;
"G1"
$PN"G1"5;
"VSS62"
$PN"141"5;
"VSS61"
$PN"139"5;
"VSS60"
$PN"136"5;
"VSS58"
$PN"132"5;
"VSS104"
$PN"240"6;
"VSS102"
$PN"235"6;
"VSS100"
$PN"230"6;
"VIN_BULK2"
$PN"146"1;
"VIN_BULK1"
$PN"145"1;
"VIN_BULK0"
$PN"1"1;
"VSS126"
$PN"288"6;
"VSS125"
$PN"286"6;
"VSS124"
$PN"284"6;
"VSS123"
$PN"281"6;
"VSS122"
$PN"279"6;
"VSS121"
$PN"277"6;
"VSS120"
$PN"275"6;
"VSS119"
$PN"273"6;
"VSS118"
$PN"270"6;
"VSS117"
$PN"268"6;
"VSS116"
$PN"266"6;
"VSS115"
$PN"264"6;
"VSS114"
$PN"262"6;
"VSS113"
$PN"259"6;
"VSS112"
$PN"257"6;
"VSS111"
$PN"255"6;
"VSS110"
$PN"253"6;
"VSS109"
$PN"251"6;
"VSS108"
$PN"248"6;
"VSS107"
$PN"246"6;
"VSS106"
$PN"244"6;
"VSS105"
$PN"242"6;
"VSS103"
$PN"237"6;
"VSS101"
$PN"233"6;
"VSS99"
$PN"228"6;
"VSS98"
$PN"226"6;
"VSS97"
$PN"224"6;
"VSS96"
$PN"222"6;
"VSS95"
$PN"219"6;
"VSS94"
$PN"216"6;
"VSS93"
$PN"214"6;
"VSS92"
$PN"212"6;
"VSS91"
$PN"210"6;
"VSS90"
$PN"208"6;
"VSS89"
$PN"206"6;
"VSS88"
$PN"204"6;
"VSS87"
$PN"202"6;
"VSS86"
$PN"199"6;
"VSS85"
$PN"197"6;
"VSS84"
$PN"195"6;
"VSS83"
$PN"193"6;
"VSS82"
$PN"191"6;
"VSS81"
$PN"188"6;
"VSS80"
$PN"186"6;
"VSS79"
$PN"184"6;
"VSS78"
$PN"182"6;
"VSS77"
$PN"180"6;
"VSS76"
$PN"177"6;
"VSS75"
$PN"175"6;
"VSS74"
$PN"173"6;
"VSS73"
$PN"171"6;
"VSS72"
$PN"169"6;
"VSS71"
$PN"166"6;
"VSS70"
$PN"164"6;
"VSS69"
$PN"162"6;
"VSS68"
$PN"160"6;
"VSS67"
$PN"158"6;
"VSS66"
$PN"155"6;
"VSS65"
$PN"153"6;
"VSS64"
$PN"151"6;
"VSS63"
$PN"143"5;
"VSS59"
$PN"134"5;
"VSS57"
$PN"130"5;
"VSS56"
$PN"128"5;
"VSS55"
$PN"125"5;
"VSS54"
$PN"123"5;
"VSS53"
$PN"121"5;
"VSS52"
$PN"119"5;
"VSS51"
$PN"117"5;
"VSS50"
$PN"114"5;
"VSS49"
$PN"112"5;
"VSS48"
$PN"110"5;
"VSS47"
$PN"108"5;
"VSS46"
$PN"106"5;
"VSS45"
$PN"103"5;
"VSS44"
$PN"101"5;
"VSS43"
$PN"99"5;
"VSS42"
$PN"97"5;
"VSS41"
$PN"95"5;
"VSS40"
$PN"92"5;
"VSS39"
$PN"90"5;
"VSS38"
$PN"88"5;
"VSS37"
$PN"85"5;
"VSS36"
$PN"83"5;
"VSS35"
$PN"81"5;
"VSS34"
$PN"79"5;
"VSS33"
$PN"77"5;
"VSS32"
$PN"75"5;
"VSS31"
$PN"73"5;
"VSS30"
$PN"71"5;
"VSS29"
$PN"69"5;
"VSS28"
$PN"67"5;
"VSS27"
$PN"65"5;
"VSS26"
$PN"63"5;
"VSS25"
$PN"61"5;
"VSS24"
$PN"59"5;
"VSS23"
$PN"57"5;
"VSS22"
$PN"54"5;
"VSS21"
$PN"52"5;
"VSS20"
$PN"50"5;
"VSS19"
$PN"48"5;
"VSS18"
$PN"46"5;
"VSS17"
$PN"43"5;
"VSS16"
$PN"41"5;
"VSS15"
$PN"39"5;
"VSS14"
$PN"37"5;
"VSS13"
$PN"35"5;
"VSS12"
$PN"32"5;
"VSS11"
$PN"30"5;
"VSS10"
$PN"28"5;
"VSS9"
$PN"26"5;
"VSS8"
$PN"24"5;
"VSS7"
$PN"21"5;
"VSS6"
$PN"19"5;
"VSS5"
$PN"17"5;
"VSS4"
$PN"15"5;
"VSS3"
$PN"13"5;
"VSS2"
$PN"10"5;
"VSS1"
$PN"8"5;
"VSS0"
$PN"6"5;
%"SCONN288_ADR50017P087CC"
"1","(-3075,2725)","0","pure_quanta","I179";
;
PART_NUMBER"DFHST8FS460"
MATERIAL"IO"
VALUE"SCONN288_ADR50017-P087CC"
PART_TYPE"SMLF"
$LOCATION"J32"
CDS_LIB"pure_quanta"
CDS_LMAN_SYM_OUTLINE"-450,1875,450,-1875"
NEEDS_NO_SIZE"TRUE"
CDS_LOCATION"J32"
$SEC"1"
CDS_SEC"1";
"DQ31_A"
$PN"194"178;
"CB7_A"
$PN"205"80;
"CB4_A"
$PN"58"177;
"CB1_A"
$PN"53"176;
"CB7_B"
$PN"236"175;
"ALERT_N \B"
$PN"62"23;
"CA0_A"
$PN"66"174;
"CA0_B"
$PN"76"173;
"CA1_A"
$PN"211"172;
"CA1_B"
$PN"221"171;
"CA2_A"
$PN"68"170;
"CA2_B"
$PN"78"169;
"CA3_A"
$PN"213"168;
"CA3_B"
$PN"223"167;
"CA4_A"
$PN"70"90;
"CA4_B"
$PN"80"166;
"CA5_A"
$PN"215"165;
"CA5_B"
$PN"225"164;
"CA6_A"
$PN"72"163;
"CA6_B"
$PN"82"162;
"CB6_A"
$PN"203"161;
"CB5_A"
$PN"60"33;
"CB3_A"
$PN"198"160;
"CB2_A"
$PN"196"159;
"CB0_A"
$PN"51"36;
"CB6_B"
$PN"234"35;
"CB5_B"
$PN"91"95;
"CB4_B"
$PN"89"78;
"CB3_B"
$PN"243"77;
"CB2_B"
$PN"241"158;
"CB1_B"
$PN"98"157;
"CB0_B"
$PN"96"79;
"CK_C \B"
$PN"218"91;
"CK_T"
$PN"217"92;
"CS0_A_N"
$PN"64"156;
"CS0_B_N"
$PN"84"155;
"CS1_A_N"
$PN"209"154;
"CS1_B_N"
$PN"229"98;
"DQ30_A"
$PN"192"153;
"DQ29_A"
$PN"49"152;
"DQ28_A"
$PN"47"97;
"DQ27_A"
$PN"187"151;
"DQ26_A"
$PN"185"150;
"DQ25_A"
$PN"42"149;
"DQ24_A"
$PN"40"148;
"DQ23_A"
$PN"183"147;
"DQ22_A"
$PN"181"146;
"DQ21_A"
$PN"38"145;
"DQ20_A"
$PN"36"144;
"DQ19_A"
$PN"176"143;
"DQ18_A"
$PN"174"142;
"DQ17_A"
$PN"31"94;
"DQ16_A"
$PN"29"93;
"DQ15_A"
$PN"172"141;
"DQ14_A"
$PN"170"140;
"DQ13_A"
$PN"27"139;
"DQ12_A"
$PN"25"138;
"DQ11_A"
$PN"165"137;
"DQ10_A"
$PN"163"81;
"DQ9_A"
$PN"20"82;
"DQ8_A"
$PN"18"83;
"DQ7_A"
$PN"161"84;
"DQ6_A"
$PN"159"136;
"DQ5_A"
$PN"16"135;
"DQ4_A"
$PN"14"134;
"DQ3_A"
$PN"154"133;
"DQ2_A"
$PN"152"132;
"DQ1_A"
$PN"9"32;
"DQ0_A"
$PN"7"131;
"DQ31_B"
$PN"287"130;
"DQ30_B"
$PN"285"129;
"DQ29_B"
$PN"142"128;
"DQ28_B"
$PN"140"31;
"DQ27_B"
$PN"280"100;
"DQ26_B"
$PN"278"99;
"DQ25_B"
$PN"135"127;
"DQ24_B"
$PN"133"126;
"DQ23_B"
$PN"276"125;
"DQ22_B"
$PN"274"124;
"DQ21_B"
$PN"131"123;
"DQ20_B"
$PN"129"122;
"DQ19_B"
$PN"269"121;
"DQ18_B"
$PN"267"120;
"DQ17_B"
$PN"124"119;
"DQ16_B"
$PN"122"118;
"DQ15_B"
$PN"265"117;
"DQ14_B"
$PN"263"116;
"DQ13_B"
$PN"120"115;
"DQ12_B"
$PN"118"114;
"DQ11_B"
$PN"258"96;
"DQ10_B"
$PN"256"113;
"DQ9_B"
$PN"113"112;
"DQ8_B"
$PN"111"111;
"DQ7_B"
$PN"254"110;
"DQ6_B"
$PN"252"109;
"DQ5_B"
$PN"109"108;
"DQ4_B"
$PN"107"107;
"DQ3_B"
$PN"247"106;
"DQ2_B"
$PN"245"105;
"DQ1_B"
$PN"102"104;
"DQ0_B"
$PN"100"103;
"HSA"
$PN"148"30;
"HSCL"
$PN"4"21;
"HSDA"
$PN"5"20;
"LBD||RSP_A_N"
$PN"86"87;
"LBS||RSP_B_N"
$PN"87"86;
"PAR_A"
$PN"74"102;
"PAR_B"
$PN"227"101;
"PWR_GOOD||FAIL_N"
$PN"147"29;
"RESET_N \B"
$PN"207"22;
"RFU6"
$PN"232"28;
"RFU5"
$PN"231"27;
"RFU4"
$PN"220"25;
"RFU3"
$PN"150"26;
"RFU2"
$PN"149"34;
"RFU1"
$PN"144"89;
"RFU0"
$PN"2"88;
"VIN_MGMT"
$PN"3"4;
%"SCONN288_ADR50017P087CC"
"2","(-400,3450)","0","pure_quanta","I180";
;
PART_NUMBER"DFHST8FS460"
VALUE"SCONN288_ADR50017-P087CC"
MATERIAL"IO"
PART_TYPE"SMLF"
LOCATION"J32"
CDS_LIB"pure_quanta"
CDS_LMAN_SYM_OUTLINE"-600,1150,600,-1150"
NEEDS_NO_SIZE"TRUE"
$SEC"2"
CDS_SEC"2";
"DQS7_A_C||TDQS7_A_C \B"
$PN"178"41;
"DQS6_A_T||TDQS6_A_T"
$PN"168"60;
"DQS8_B_T||TDQS8_B_T"
$PN"283"68;
"DQS8_B_C||TDQS8_B_C \B"
$PN"282"49;
"DQS7_B_T||TDQS7_B_T"
$PN"272"69;
"DQS0_A_C \B"
$PN"12"47;
"DQS0_A_T"
$PN"11"66;
"DQS0_B_C \B"
$PN"105"55;
"DQS0_B_T"
$PN"104"76;
"DQS1_A_C \B"
$PN"23"45;
"DQS1_A_T"
$PN"22"65;
"DQS1_B_C \B"
$PN"116"56;
"DQS1_B_T"
$PN"115"75;
"DQS2_A_C \B"
$PN"34"46;
"DQS2_A_T"
$PN"33"64;
"DQS2_B_C \B"
$PN"127"54;
"DQS2_B_T"
$PN"126"74;
"DQS3_A_C \B"
$PN"45"44;
"DQS3_A_T"
$PN"44"63;
"DQS3_B_C \B"
$PN"138"53;
"DQS3_B_T"
$PN"137"73;
"DQS4_A_C \B"
$PN"56"43;
"DQS4_A_T"
$PN"55"62;
"DQS4_B_C \B"
$PN"238"52;
"DQS4_B_T"
$PN"239"72;
"DQS5_A_C||TDQS5_A_C||DQS5_A_T||TDQS5_A_T \B"
$PN"156"42;
"DQS5_A_T||TDQS5_A_T"
$PN"157"61;
"DQS5_B_C||TDQS5_B_C \B"
$PN"249"37;
"DQS5_B_T||TDQS5_B_T"
$PN"250"71;
"DQS6_A_C||TDQS6_A_C||DQS6_A_T||TDQS6_A_T \B"
$PN"167"40;
"DQS6_B_C||TDQS6_B_C \B"
$PN"260"51;
"DQS6_B_T||TDQS6_B_T"
$PN"261"70;
"DQS7_A_T||TDQS7_A_T"
$PN"179"59;
"DQS7_B_C||TDQS7_B_C \B"
$PN"271"50;
"DQS8_A_C||TDQS8_A_C \B"
$PN"189"39;
"DQS8_A_T||TDQS8_A_T"
$PN"190"58;
"DQS9_A_C||TDQS9_A_C \B"
$PN"200"38;
"DQS9_A_T||TDQS9_A_T"
$PN"201"57;
"DQS9_B_C||TDQS9_B_C \B"
$PN"94"48;
"DQS9_B_T||TDQS9_B_T||DBI4_B_N"
$PN"93"67;
%"Q_RES"
"1","(-4900,1750)","0","pure_quanta","I182";
;
PART_NUMBER"CS04992FB07"
VALUE"49.9"
MATERIAL"CHIP"
$LOCATION"R3906"
CDS_LIB"pure_quanta"
PACK_TYPE"0402LF"
TOLERANCE"1%"
WATTAGE"1/16W"
CDS_LOCATION"R3906"
$SEC"1"
CDS_SEC"1";
"B"
$PN"2"24;
"A"
$PN"1"21;
%"Q_RES"
"2","(-3675,300)","0","pure_quanta","I2";
;
PART_NUMBER"CS41962FB03"
MATERIAL"CHIP"
PACK_TYPE"0402LF"
WATTAGE"1/16W"
TOLERANCE"1%"
VALUE"196K"
$LOCATION"R72"
CDS_LIB"pure_quanta"
$LOCATION"R72"
CDS_LOCATION"R72"
$SEC"1"
CDS_SEC"1";
"A"
$PN"1"85;
"B"
$PN"2"9;
%"TAP"
"1","(-3900,2400)","2","standard","I22";
;
CDS_LIB"standard"
BODY_TYPE"PLUMBING"
HDL_TAP"TRUE";
"B \NAC \NWC"12;
"S \NAC"
BN"3"77;
%"TAP"
"1","(-3900,2300)","2","standard","I23";
;
CDS_LIB"standard"
BODY_TYPE"PLUMBING"
HDL_TAP"TRUE";
"B \NAC \NWC"12;
"S \NAC"
BN"1"157;
%"TAP"
"1","(-3900,2350)","2","standard","I24";
;
CDS_LIB"standard"
BODY_TYPE"PLUMBING"
HDL_TAP"TRUE";
"B \NAC \NWC"12;
"S \NAC"
BN"2"158;
%"TAP"
"1","(-3900,2550)","2","standard","I25";
;
CDS_LIB"standard"
BODY_TYPE"PLUMBING"
HDL_TAP"TRUE";
"B \NAC \NWC"12;
"S \NAC"
BN"6"35;
%"TAP"
"1","(-3900,2800)","2","standard","I26";
;
CDS_LIB"standard"
BODY_TYPE"PLUMBING"
HDL_TAP"TRUE";
"B \NAC \NWC"11;
"S \NAC"
BN"2"159;
%"TAP"
"1","(-3900,2750)","2","standard","I27";
;
CDS_LIB"standard"
BODY_TYPE"PLUMBING"
HDL_TAP"TRUE";
"B \NAC \NWC"11;
"S \NAC"
BN"1"176;
%"TAP"
"1","(-3900,2700)","2","standard","I28";
;
CDS_LIB"standard"
BODY_TYPE"PLUMBING"
HDL_TAP"TRUE";
"B \NAC \NWC"11;
"S \NAC"
BN"0"36;
%"TAP"
"1","(-3900,2600)","2","standard","I29";
;
CDS_LIB"standard"
BODY_TYPE"PLUMBING"
HDL_TAP"TRUE";
"B \NAC \NWC"12;
"S \NAC"
BN"7"175;
%"TAP"
"1","(-3900,2900)","2","standard","I30";
;
CDS_LIB"standard"
BODY_TYPE"PLUMBING"
HDL_TAP"TRUE";
"B \NAC \NWC"11;
"S \NAC"
BN"4"177;
%"TAP"
"1","(-3900,2850)","2","standard","I31";
;
CDS_LIB"standard"
BODY_TYPE"PLUMBING"
HDL_TAP"TRUE";
"B \NAC \NWC"11;
"S \NAC"
BN"3"160;
%"TAP"
"1","(-3900,3000)","2","standard","I32";
;
CDS_LIB"standard"
BODY_TYPE"PLUMBING"
HDL_TAP"TRUE";
"B \NAC \NWC"11;
"S \NAC"
BN"6"161;
%"TAP"
"1","(-3900,3050)","2","standard","I33";
;
CDS_LIB"standard"
BODY_TYPE"PLUMBING"
HDL_TAP"TRUE";
"B \NAC \NWC"11;
"S \NAC"
BN"7"80;
%"TAP"
"1","(-3900,2950)","2","standard","I34";
;
CDS_LIB"standard"
BODY_TYPE"PLUMBING"
HDL_TAP"TRUE";
"B \NAC \NWC"11;
"S \NAC"
BN"5"33;
%"TAP"
"1","(-3900,3750)","2","standard","I35";
;
CDS_LIB"standard"
BODY_TYPE"PLUMBING"
HDL_TAP"TRUE";
"B \NAC \NWC"14;
"S \NAC"
BN"0"173;
%"TAP"
"1","(-3900,3800)","2","standard","I36";
;
CDS_LIB"standard"
BODY_TYPE"PLUMBING"
HDL_TAP"TRUE";
"B \NAC \NWC"14;
"S \NAC"
BN"1"171;
%"TAP"
"1","(-3900,3850)","2","standard","I37";
;
CDS_LIB"standard"
BODY_TYPE"PLUMBING"
HDL_TAP"TRUE";
"B \NAC \NWC"14;
"S \NAC"
BN"2"169;
%"TAP"
"1","(-3900,3950)","2","standard","I38";
;
CDS_LIB"standard"
BODY_TYPE"PLUMBING"
HDL_TAP"TRUE";
"B \NAC \NWC"14;
"S \NAC"
BN"4"166;
%"TAP"
"1","(-3900,3900)","2","standard","I39";
;
CDS_LIB"standard"
BODY_TYPE"PLUMBING"
HDL_TAP"TRUE";
"B \NAC \NWC"14;
"S \NAC"
BN"3"167;
%"TAP"
"1","(-3900,4050)","2","standard","I40";
;
CDS_LIB"standard"
BODY_TYPE"PLUMBING"
HDL_TAP"TRUE";
"B \NAC \NWC"14;
"S \NAC"
BN"6"162;
%"TAP"
"1","(-3900,4000)","2","standard","I41";
;
CDS_LIB"standard"
BODY_TYPE"PLUMBING"
HDL_TAP"TRUE";
"B \NAC \NWC"14;
"S \NAC"
BN"5"164;
%"TAP"
"1","(-3900,4300)","2","standard","I42";
;
CDS_LIB"standard"
BODY_TYPE"PLUMBING"
HDL_TAP"TRUE";
"B \NAC \NWC"13;
"S \NAC"
BN"3"168;
%"TAP"
"1","(-3900,4250)","2","standard","I43";
;
CDS_LIB"standard"
BODY_TYPE"PLUMBING"
HDL_TAP"TRUE";
"B \NAC \NWC"13;
"S \NAC"
BN"2"170;
%"TAP"
"1","(-3900,4200)","2","standard","I44";
;
CDS_LIB"standard"
BODY_TYPE"PLUMBING"
HDL_TAP"TRUE";
"B \NAC \NWC"13;
"S \NAC"
BN"1"172;
%"TAP"
"1","(-3900,4150)","2","standard","I45";
;
CDS_LIB"standard"
BODY_TYPE"PLUMBING"
HDL_TAP"TRUE";
"B \NAC \NWC"13;
"S \NAC"
BN"0"174;
%"TAP"
"1","(-2250,1250)","0","standard","I46";
;
CDS_LIB"standard"
BODY_TYPE"PLUMBING"
HDL_TAP"TRUE";
"B \NAC \NWC"15;
"S \NAC"
BN"0"103;
%"TAP"
"1","(-2250,1300)","0","standard","I47";
;
CDS_LIB"standard"
BODY_TYPE"PLUMBING"
HDL_TAP"TRUE";
"B \NAC \NWC"15;
"S \NAC"
BN"1"104;
%"TAP"
"1","(-2250,1350)","0","standard","I48";
;
CDS_LIB"standard"
BODY_TYPE"PLUMBING"
HDL_TAP"TRUE";
"B \NAC \NWC"15;
"S \NAC"
BN"2"105;
%"TAP"
"1","(-2250,1400)","0","standard","I49";
;
CDS_LIB"standard"
BODY_TYPE"PLUMBING"
HDL_TAP"TRUE";
"B \NAC \NWC"15;
"S \NAC"
BN"3"106;
%"TAP"
"1","(-2250,1550)","0","standard","I50";
;
CDS_LIB"standard"
BODY_TYPE"PLUMBING"
HDL_TAP"TRUE";
"B \NAC \NWC"15;
"S \NAC"
BN"6"109;
%"TAP"
"1","(-2250,1450)","0","standard","I51";
;
CDS_LIB"standard"
BODY_TYPE"PLUMBING"
HDL_TAP"TRUE";
"B \NAC \NWC"15;
"S \NAC"
BN"4"107;
%"TAP"
"1","(-2250,1500)","0","standard","I52";
;
CDS_LIB"standard"
BODY_TYPE"PLUMBING"
HDL_TAP"TRUE";
"B \NAC \NWC"15;
"S \NAC"
BN"5"108;
%"TAP"
"1","(-2250,1650)","0","standard","I53";
;
CDS_LIB"standard"
BODY_TYPE"PLUMBING"
HDL_TAP"TRUE";
"B \NAC \NWC"15;
"S \NAC"
BN"8"111;
%"TAP"
"1","(-2250,1750)","0","standard","I54";
;
CDS_LIB"standard"
BODY_TYPE"PLUMBING"
HDL_TAP"TRUE";
"B \NAC \NWC"15;
"S \NAC"
BN"10"113;
%"TAP"
"1","(-2250,1800)","0","standard","I55";
;
CDS_LIB"standard"
BODY_TYPE"PLUMBING"
HDL_TAP"TRUE";
"B \NAC \NWC"15;
"S \NAC"
BN"11"96;
%"TAP"
"1","(-2250,1700)","0","standard","I56";
;
CDS_LIB"standard"
BODY_TYPE"PLUMBING"
HDL_TAP"TRUE";
"B \NAC \NWC"15;
"S \NAC"
BN"9"112;
%"TAP"
"1","(-2250,1600)","0","standard","I57";
;
CDS_LIB"standard"
BODY_TYPE"PLUMBING"
HDL_TAP"TRUE";
"B \NAC \NWC"15;
"S \NAC"
BN"7"110;
%"TAP"
"1","(-2250,1900)","0","standard","I58";
;
CDS_LIB"standard"
BODY_TYPE"PLUMBING"
HDL_TAP"TRUE";
"B \NAC \NWC"15;
"S \NAC"
BN"13"115;
%"TAP"
"1","(-2250,2000)","0","standard","I59";
;
CDS_LIB"standard"
BODY_TYPE"PLUMBING"
HDL_TAP"TRUE";
"B \NAC \NWC"15;
"S \NAC"
BN"15"117;
%"TAP"
"1","(-2250,2050)","0","standard","I60";
;
CDS_LIB"standard"
BODY_TYPE"PLUMBING"
HDL_TAP"TRUE";
"B \NAC \NWC"15;
"S \NAC"
BN"16"118;
%"TAP"
"1","(-2250,1950)","0","standard","I61";
;
CDS_LIB"standard"
BODY_TYPE"PLUMBING"
HDL_TAP"TRUE";
"B \NAC \NWC"15;
"S \NAC"
BN"14"116;
%"TAP"
"1","(-2250,1850)","0","standard","I62";
;
CDS_LIB"standard"
BODY_TYPE"PLUMBING"
HDL_TAP"TRUE";
"B \NAC \NWC"15;
"S \NAC"
BN"12"114;
%"TAP"
"1","(-2250,2200)","0","standard","I63";
;
CDS_LIB"standard"
BODY_TYPE"PLUMBING"
HDL_TAP"TRUE";
"B \NAC \NWC"15;
"S \NAC"
BN"19"121;
%"TAP"
"1","(-2250,2250)","0","standard","I64";
;
CDS_LIB"standard"
BODY_TYPE"PLUMBING"
HDL_TAP"TRUE";
"B \NAC \NWC"15;
"S \NAC"
BN"20"122;
%"TAP"
"1","(-2250,2300)","0","standard","I65";
;
CDS_LIB"standard"
BODY_TYPE"PLUMBING"
HDL_TAP"TRUE";
"B \NAC \NWC"15;
"S \NAC"
BN"21"123;
%"TAP"
"1","(-2250,2150)","0","standard","I66";
;
CDS_LIB"standard"
BODY_TYPE"PLUMBING"
HDL_TAP"TRUE";
"B \NAC \NWC"15;
"S \NAC"
BN"18"120;
%"TAP"
"1","(-2250,2100)","0","standard","I67";
;
CDS_LIB"standard"
BODY_TYPE"PLUMBING"
HDL_TAP"TRUE";
"B \NAC \NWC"15;
"S \NAC"
BN"17"119;
%"TAP"
"1","(-3900,4350)","2","standard","I68";
;
CDS_LIB"standard"
BODY_TYPE"PLUMBING"
HDL_TAP"TRUE";
"B \NAC \NWC"13;
"S \NAC"
BN"4"90;
%"TAP"
"1","(-2250,2500)","0","standard","I69";
;
CDS_LIB"standard"
BODY_TYPE"PLUMBING"
HDL_TAP"TRUE";
"B \NAC \NWC"15;
"S \NAC"
BN"25"127;
%"TAP"
"1","(-2250,2550)","0","standard","I70";
;
CDS_LIB"standard"
BODY_TYPE"PLUMBING"
HDL_TAP"TRUE";
"B \NAC \NWC"15;
"S \NAC"
BN"26"99;
%"TAP"
"1","(-2250,2450)","0","standard","I71";
;
CDS_LIB"standard"
BODY_TYPE"PLUMBING"
HDL_TAP"TRUE";
"B \NAC \NWC"15;
"S \NAC"
BN"24"126;
%"TAP"
"1","(-2250,2400)","0","standard","I72";
;
CDS_LIB"standard"
BODY_TYPE"PLUMBING"
HDL_TAP"TRUE";
"B \NAC \NWC"15;
"S \NAC"
BN"23"125;
%"TAP"
"1","(-2250,2350)","0","standard","I73";
;
CDS_LIB"standard"
BODY_TYPE"PLUMBING"
HDL_TAP"TRUE";
"B \NAC \NWC"15;
"S \NAC"
BN"22"124;
%"TAP"
"1","(-2250,2750)","0","standard","I74";
;
CDS_LIB"standard"
BODY_TYPE"PLUMBING"
HDL_TAP"TRUE";
"B \NAC \NWC"15;
"S \NAC"
BN"30"129;
%"TAP"
"1","(-2250,2800)","0","standard","I75";
;
CDS_LIB"standard"
BODY_TYPE"PLUMBING"
HDL_TAP"TRUE";
"B \NAC \NWC"15;
"S \NAC"
BN"31"130;
%"TAP"
"1","(-2250,2700)","0","standard","I76";
;
CDS_LIB"standard"
BODY_TYPE"PLUMBING"
HDL_TAP"TRUE";
"B \NAC \NWC"15;
"S \NAC"
BN"29"128;
%"TAP"
"1","(-2250,2600)","0","standard","I77";
;
CDS_LIB"standard"
BODY_TYPE"PLUMBING"
HDL_TAP"TRUE";
"B \NAC \NWC"15;
"S \NAC"
BN"27"100;
%"TAP"
"1","(-2250,2650)","0","standard","I78";
;
CDS_LIB"standard"
BODY_TYPE"PLUMBING"
HDL_TAP"TRUE";
"B \NAC \NWC"15;
"S \NAC"
BN"28"31;
%"TAP"
"1","(-2250,2900)","0","standard","I79";
;
CDS_LIB"standard"
BODY_TYPE"PLUMBING"
HDL_TAP"TRUE";
"B \NAC \NWC"10;
"S \NAC"
BN"0"131;
%"TAP"
"1","(-2250,3000)","0","standard","I80";
;
CDS_LIB"standard"
BODY_TYPE"PLUMBING"
HDL_TAP"TRUE";
"B \NAC \NWC"10;
"S \NAC"
BN"2"132;
%"TAP"
"1","(-2250,3050)","0","standard","I81";
;
CDS_LIB"standard"
BODY_TYPE"PLUMBING"
HDL_TAP"TRUE";
"B \NAC \NWC"10;
"S \NAC"
BN"3"133;
%"TAP"
"1","(-2250,2950)","0","standard","I82";
;
CDS_LIB"standard"
BODY_TYPE"PLUMBING"
HDL_TAP"TRUE";
"B \NAC \NWC"10;
"S \NAC"
BN"1"32;
%"TAP"
"1","(-2250,3200)","0","standard","I83";
;
CDS_LIB"standard"
BODY_TYPE"PLUMBING"
HDL_TAP"TRUE";
"B \NAC \NWC"10;
"S \NAC"
BN"6"136;
%"TAP"
"1","(-2250,3300)","0","standard","I84";
;
CDS_LIB"standard"
BODY_TYPE"PLUMBING"
HDL_TAP"TRUE";
"B \NAC \NWC"10;
"S \NAC"
BN"8"83;
%"TAP"
"1","(-2250,3250)","0","standard","I85";
;
CDS_LIB"standard"
BODY_TYPE"PLUMBING"
HDL_TAP"TRUE";
"B \NAC \NWC"10;
"S \NAC"
BN"7"84;
%"TAP"
"1","(-2250,3150)","0","standard","I86";
;
CDS_LIB"standard"
BODY_TYPE"PLUMBING"
HDL_TAP"TRUE";
"B \NAC \NWC"10;
"S \NAC"
BN"5"135;
%"TAP"
"1","(-2250,3100)","0","standard","I87";
;
CDS_LIB"standard"
BODY_TYPE"PLUMBING"
HDL_TAP"TRUE";
"B \NAC \NWC"10;
"S \NAC"
BN"4"134;
%"TAP"
"1","(-2250,3400)","0","standard","I88";
;
CDS_LIB"standard"
BODY_TYPE"PLUMBING"
HDL_TAP"TRUE";
"B \NAC \NWC"10;
"S \NAC"
BN"10"81;
%"TAP"
"1","(-2250,3350)","0","standard","I89";
;
CDS_LIB"standard"
BODY_TYPE"PLUMBING"
HDL_TAP"TRUE";
"B \NAC \NWC"10;
"S \NAC"
BN"9"82;
%"TAP"
"1","(-2250,3450)","0","standard","I90";
;
CDS_LIB"standard"
BODY_TYPE"PLUMBING"
HDL_TAP"TRUE";
"B \NAC \NWC"10;
"S \NAC"
BN"11"137;
%"TAP"
"1","(-2250,3500)","0","standard","I91";
;
CDS_LIB"standard"
BODY_TYPE"PLUMBING"
HDL_TAP"TRUE";
"B \NAC \NWC"10;
"S \NAC"
BN"12"138;
%"TAP"
"1","(-2250,3600)","0","standard","I92";
;
CDS_LIB"standard"
BODY_TYPE"PLUMBING"
HDL_TAP"TRUE";
"B \NAC \NWC"10;
"S \NAC"
BN"14"140;
%"TAP"
"1","(-2250,3550)","0","standard","I93";
;
CDS_LIB"standard"
BODY_TYPE"PLUMBING"
HDL_TAP"TRUE";
"B \NAC \NWC"10;
"S \NAC"
BN"13"139;
%"TAP"
"1","(-2250,3800)","0","standard","I94";
;
CDS_LIB"standard"
BODY_TYPE"PLUMBING"
HDL_TAP"TRUE";
"B \NAC \NWC"10;
"S \NAC"
BN"18"142;
%"TAP"
"1","(-2250,3750)","0","standard","I95";
;
CDS_LIB"standard"
BODY_TYPE"PLUMBING"
HDL_TAP"TRUE";
"B \NAC \NWC"10;
"S \NAC"
BN"17"94;
%"TAP"
"1","(-2250,3850)","0","standard","I96";
;
CDS_LIB"standard"
BODY_TYPE"PLUMBING"
HDL_TAP"TRUE";
"B \NAC \NWC"10;
"S \NAC"
BN"19"143;
%"TAP"
"1","(-2250,3700)","0","standard","I97";
;
CDS_LIB"standard"
BODY_TYPE"PLUMBING"
HDL_TAP"TRUE";
"B \NAC \NWC"10;
"S \NAC"
BN"16"93;
%"TAP"
"1","(-2250,3650)","0","standard","I98";
;
CDS_LIB"standard"
BODY_TYPE"PLUMBING"
HDL_TAP"TRUE";
"B \NAC \NWC"10;
"S \NAC"
BN"15"141;
%"TAP"
"1","(-2250,3950)","0","standard","I99";
;
CDS_LIB"standard"
BODY_TYPE"PLUMBING"
HDL_TAP"TRUE";
"B \NAC \NWC"10;
"S \NAC"
BN"21"145;
END.
